(kicad_pcb
	(version 20241229)
	(generator "pcbnew")
	(generator_version "9.0")
	(general
		(thickness 1.6)
		(legacy_teardrops no)
	)
	(paper "A4")
	(title_block
		(title "OCuLink to PCIe adapter")
		(date "2025-06-18")
		(rev "1.0.0")
		(company "Antmicro Ltd")
		(comment 1 "www.antmicro.com")
		(comment 9 "footprints 49-49 of 159")
	)
	(layers
		(0 "F.Cu" signal)
		(4 "In1.Cu" signal)
		(6 "In2.Cu" signal)
		(2 "B.Cu" signal)
		(9 "F.Adhes" user "F.Adhesive")
		(11 "B.Adhes" user "B.Adhesive")
		(13 "F.Paste" user)
		(15 "B.Paste" user)
		(5 "F.SilkS" user "F.Silkscreen")
		(7 "B.SilkS" user "B.Silkscreen")
		(1 "F.Mask" user)
		(3 "B.Mask" user)
		(17 "Dwgs.User" user "User.Drawings")
		(19 "Cmts.User" user "User.Comments")
		(21 "Eco1.User" user "User.Eco1")
		(23 "Eco2.User" user "User.Eco2")
		(25 "Edge.Cuts" user)
		(27 "Margin" user)
		(31 "F.CrtYd" user "F.Courtyard")
		(29 "B.CrtYd" user "B.Courtyard")
		(35 "F.Fab" user)
		(33 "B.Fab" user)
	)
	(footprint "antmicro-footprints:SOT-23-3"
		(layer "F.Cu")
		(at 121.125 147.604999 90)
		(property "Reference" "Q2"
			(at 1.004999 0.675 0)
			(layer "F.SilkS")
			(effects
				(font
					(size 0.7 0.7)
					(thickness 0.15)
				)
				(justify left bottom)
			)
		)
		(property "Value" "BSS138-7-F"
			(at -1.9 2.7 90)
			(layer "F.Fab")
			(effects
				(font
					(size 0.7 0.7)
					(thickness 0.15)
				)
				(justify left bottom)
			)
		)
		(property "Datasheet" "https://www.diodes.com/assets/Datasheets/ds30144.pdf"
			(at 0 0 90)
			(layer "F.Fab")
			(hide yes)
			(effects
				(font
					(size 1.27 1.27)
					(thickness 0.15)
				)
			)
		)
		(property "Description" "Power MOSFET, N Channel, 50 V, 200 mA, 1.4 ohm, SOT-23, Surface Mount"
			(at 0 0 90)
			(layer "F.Fab")
			(hide yes)
			(effects
				(font
					(size 1.27 1.27)
					(thickness 0.15)
				)
			)
		)
		(property "MPN" "BSS138-7-F"
			(at 0 0 90)
			(unlocked yes)
			(layer "F.Fab")
			(hide yes)
			(effects
				(font
					(size 1 1)
					(thickness 0.15)
				)
			)
		)
		(property "Manufacturer" "Diodes Incorporated"
			(at 0 0 90)
			(unlocked yes)
			(layer "F.Fab")
			(hide yes)
			(effects
				(font
					(size 1 1)
					(thickness 0.15)
				)
			)
		)
		(property "Author" "Antmicro"
			(at 0 0 90)
			(unlocked yes)
			(layer "F.Fab")
			(hide yes)
			(effects
				(font
					(size 1 1)
					(thickness 0.15)
				)
			)
		)
		(property "License" "Apache-2.0"
			(at 0 0 90)
			(unlocked yes)
			(layer "F.Fab")
			(hide yes)
			(effects
				(font
					(size 1 1)
					(thickness 0.15)
				)
			)
		)
		(sheetname "/Power/")
		(sheetfile "power.kicad_sch")
		(attr smd)
		(fp_line
			(start 0.7 -1.5)
			(end -0.7 -1.5)
			(stroke
				(width 0.15)
				(type solid)
			)
			(layer "F.SilkS")
		)
		(fp_line
			(start -0.85 -1.35)
			(end -0.7 -1.5)
			(stroke
				(width 0.15)
				(type solid)
			)
			(layer "F.SilkS")
		)
		(fp_line
			(start -1.45 -1.35)
			(end -0.85 -1.35)
			(stroke
				(width 0.15)
				(type solid)
			)
			(layer "F.SilkS")
		)
		(fp_line
			(start 0.7 -0.4)
			(end 0.7 -1.5)
			(stroke
				(width 0.15)
				(type solid)
			)
			(layer "F.SilkS")
		)
		(fp_line
			(start 0.7 0.4)
			(end 0.7 1.5)
			(stroke
				(width 0.15)
				(type solid)
			)
			(layer "F.SilkS")
		)
		(fp_line
			(start 0.7 1.5)
			(end -0.7 1.5)
			(stroke
				(width 0.15)
				(type solid)
			)
			(layer "F.SilkS")
		)
		(fp_line
			(start -0.7 1.5)
			(end -0.7 1.35)
			(stroke
				(width 0.15)
				(type solid)
			)
			(layer "F.SilkS")
		)
		(fp_line
			(start 0.825 -1.6)
			(end 0.825 -0.45)
			(stroke
				(width 0.05)
				(type solid)
			)
			(layer "F.CrtYd")
		)
		(fp_line
			(start -0.9 -1.6)
			(end 0.825 -1.6)
			(stroke
				(width 0.05)
				(type solid)
			)
			(layer "F.CrtYd")
		)
		(fp_line
			(start -0.9 -1.6)
			(end -0.9 -1.4)
			(stroke
				(width 0.05)
				(type solid)
			)
			(layer "F.CrtYd")
		)
		(fp_line
			(start -0.9 -1.4)
			(end -1.75 -1.4)
			(stroke
				(width 0.05)
				(type solid)
			)
			(layer "F.CrtYd")
		)
		(fp_line
			(start -0.85 -0.5)
			(end -1.75 -0.5)
			(stroke
				(width 0.05)
				(type solid)
			)
			(layer "F.CrtYd")
		)
		(fp_line
			(start -1.75 -0.5)
			(end -1.75 -1.4)
			(stroke
				(width 0.05)
				(type solid)
			)
			(layer "F.CrtYd")
		)
		(fp_line
			(start 1.75 -0.45)
			(end 1.75 0.45)
			(stroke
				(width 0.05)
				(type solid)
			)
			(layer "F.CrtYd")
		)
		(fp_line
			(start 0.825 -0.45)
			(end 1.75 -0.45)
			(stroke
				(width 0.05)
				(type solid)
			)
			(layer "F.CrtYd")
		)
		(fp_line
			(start 1.75 0.45)
			(end 0.85 0.45)
			(stroke
				(width 0.05)
				(type solid)
			)
			(layer "F.CrtYd")
		)
		(fp_line
			(start 0.85 0.45)
			(end 0.85 1.65)
			(stroke
				(width 0.05)
				(type solid)
			)
			(layer "F.CrtYd")
		)
		(fp_line
			(start -0.85 0.5)
			(end -0.85 -0.5)
			(stroke
				(width 0.05)
				(type solid)
			)
			(layer "F.CrtYd")
		)
		(fp_line
			(start -1.75 0.5)
			(end -0.85 0.5)
			(stroke
				(width 0.05)
				(type solid)
			)
			(layer "F.CrtYd")
		)
		(fp_line
			(start -0.85 1.4)
			(end -1.75 1.4)
			(stroke
				(width 0.05)
				(type solid)
			)
			(layer "F.CrtYd")
		)
		(fp_line
			(start -1.75 1.4)
			(end -1.75 0.5)
			(stroke
				(width 0.05)
				(type solid)
			)
			(layer "F.CrtYd")
		)
		(fp_line
			(start 0.85 1.65)
			(end -0.85 1.65)
			(stroke
				(width 0.05)
				(type solid)
			)
			(layer "F.CrtYd")
		)
		(fp_line
			(start -0.85 1.65)
			(end -0.85 1.4)
			(stroke
				(width 0.05)
				(type solid)
			)
			(layer "F.CrtYd")
		)
		(fp_line
			(start -0.437 -1.526)
			(end 0.688 -1.526)
			(stroke
				(width 0.15)
				(type solid)
			)
			(layer "F.Fab")
		)
		(fp_line
			(start -0.437 -1.526)
			(end -0.712 -1.325)
			(stroke
				(width 0.15)
				(type solid)
			)
			(layer "F.Fab")
		)
		(fp_line
			(start -0.712 -1.325)
			(end -0.712 1.523)
			(stroke
				(width 0.15)
				(type solid)
			)
			(layer "F.Fab")
		)
		(fp_line
			(start 0.688 1.519)
			(end 0.688 -1.52)
			(stroke
				(width 0.15)
				(type solid)
			)
			(layer "F.Fab")
		)
		(fp_line
			(start -0.712 1.519)
			(end 0.688 1.519)
			(stroke
				(width 0.15)
				(type solid)
			)
			(layer "F.Fab")
		)
		(fp_text user "License: Apache-2.0"
			(at -1.8 6.8 90)
			(layer "F.Fab")
			(effects
				(font
					(size 0.7 0.7)
					(thickness 0.15)
				)
				(justify left bottom)
			)
		)
		(fp_text user "${REFERENCE}"
			(at 0.000001 0.025 90)
			(layer "F.Fab")
			(effects
				(font
					(size 0.7 0.7)
					(thickness 0.15)
				)
				(justify left bottom)
			)
		)
		(fp_text user "Author: Antmicro"
			(at -1.837 5.3 90)
			(layer "F.Fab")
			(effects
				(font
					(size 0.7 0.7)
					(thickness 0.15)
				)
				(justify left bottom)
			)
		)
		(pad "1" smd roundrect
			(at -1.1 -0.951 90)
			(size 1 0.6)
			(layers "F.Cu" "F.Mask" "F.Paste")
			(roundrect_rratio 0.15)
			(net 105 "/Power/3V3_PG")
			(pinfunction "G")
			(pintype "input")
		)
		(pad "2" smd roundrect
			(at -1.1 0.949 90)
			(size 1 0.6)
			(layers "F.Cu" "F.Mask" "F.Paste")
			(roundrect_rratio 0.15)
			(net 66 "GND")
			(pinfunction "S")
			(pintype "passive")
		)
		(pad "3" smd roundrect
			(at 1.1 -0.0005 90)
			(size 1 0.6)
			(layers "F.Cu" "F.Mask" "F.Paste")
			(roundrect_rratio 0.15)
			(net 99 "/OCuLink/~{CPRSNT}")
			(pinfunction "D")
			(pintype "passive")
		)
	)
)
